#ISCELL
  cls sheet_a1 *
  *
#CELL
  passive resistor *
  page516_i1
#CELL
  passive capacitor *
  page516_i10
#CELL
  passive capacitor *
  page516_i11
#CELL
  passive resistor *
  page516_i12
#CELL
  passive capacitor *
  page516_i13
#CELL
  passive resistor *
  page516_i14
#CELL
  passive capacitor *
  page516_i15
#CELL
  passive resistor *
  page516_i16
#CELL
  passive ferritebead *
  page516_i17
#CELL
  passive capacitor *
  page516_i18
#CELL
  passive capacitor *
  page516_i19
#ISCELL
  cls vcc *
  page516_i2
#CELL
  passive capacitor *
  page516_i20
#ISCELL
  cls gnd_sg *
  page516_i21
#CELL
  passive capacitor *
  page516_i22
#ISCELL
  cls gnd_sg *
  page516_i23
#CELL
  mech solder_preform *
  page516_i24
#CELL
  passive resistor *
  page516_i25
#CELL
  passive resistor *
  page516_i26
#CELL
  passive capacitor *
  page516_i27
#CELL
  passive resistor *
  page516_i28
#CELL
  passive capacitor *
  page516_i29
#ISCELL
  cls gnd_sg *
  page516_i3
#CELL
  passive resistor *
  page516_i30
#CELL
  passive resistor *
  page516_i31
#CELL
  passive capacitor *
  page516_i32
#CELL
  passive capacitor *
  page516_i33
#ISCELL
  cls gnd_sg *
  page516_i34
#CELL
  passive capacitor *
  page516_i35
#CELL
  passive inductor_2 *
  page516_i36
#CELL
  passive capacitor *
  page516_i37
#CELL
  passive resistor *
  page516_i38
#ISCELL
  cls gnd_sg *
  page516_i39
#CELL
  passive capacitor *
  page516_i4
#CELL
  passive capacitor *
  page516_i40
#ISCELL
  cls vcc *
  page516_i41
#CELL
  stdlogic tps54824rnvr_vqfn18 *
  page516_i42
#ISCELL
  cls offpage_in *
  page516_i43
#CELL
  passive resistor *
  page516_i44
#CELL
  passive resistor *
  page516_i45
#ISCELL
  cls offpage_out *
  page516_i46
#ISCELL
  cls vcc *
  page516_i5
#ISCELL
  cls gnd_sg *
  page516_i6
#CELL
  passive capacitor *
  page516_i7
#ISCELL
  cls gnd_sg *
  page516_i8
#CELL
  passive resistor *
  page516_i9
